# BASEBOARD_FAB2 (Tioga Pass) — schematic netlist excerpt (pin names and nets, part order shuffled) for the footprints in the layout excerpt that follows; sources: Cadence DE-HDL packaged netlist, KiCad conversion of Wiwynn_Tioga_Pass_MB.brd

C8P6  CAP  22UF 4V 20% X6S  pkg 0805LF  page 76 : A = PVSA_CPU1 ; B = GND
C6P10  CAP_A  0.1UF 16V 10% X7R  pkg 0402V  page 102 : A = P3V3_DB1200 ; B = GND
R2N18  RES  1.00K 1% CHIP  pkg 0402  page 164 : A = FM_BOARD_SKU_ID4 ; B = GND

(kicad_pcb
	(version 20260206)
	(generator "pcbnew")
	(generator_version "10.0")
	(general
		(thickness 1.6)
		(legacy_teardrops no)
	)
	(paper "A4")
	(title_block
		(title "Wiwynn_Tioga_Pass_MB.brd")
		(comment 1 "Tioga Pass / footprints 3144-3146 of 4770")
	)
	(layers
		(0 "F.Cu" signal "TOP")
		(4 "In1.Cu" signal "L2GND")
		(6 "In2.Cu" signal "L3")
		(8 "In3.Cu" signal "L4GND")
		(10 "In4.Cu" signal "L5")
		(12 "In5.Cu" signal "L6GND")
		(14 "In6.Cu" signal "L7VCC")
		(16 "In7.Cu" signal "L8VCC")
		(18 "In8.Cu" signal "L9GND")
		(20 "In9.Cu" signal "L10")
		(22 "In10.Cu" signal "L11GND")
		(24 "In11.Cu" signal "L12")
		(26 "In12.Cu" signal "L13GND")
		(2 "B.Cu" signal "BOTTOM")
		(9 "F.Adhes" user "F.Adhesive")
		(11 "B.Adhes" user "B.Adhesive")
		(13 "F.Paste" user "Package Geometry/Pastemask Top")
		(15 "B.Paste" user "Package Geometry/Pastemask Bottom")
		(5 "F.SilkS" user "Ref Des/Silkscreen Top")
		(7 "B.SilkS" user "Ref Des/Silkscreen Bottom")
		(1 "F.Mask" user "Board Geometry/Soldermask Top")
		(3 "B.Mask" user "Board Geometry/Soldermask Bottom")
		(17 "Dwgs.User" user "User.Drawings")
		(19 "Cmts.User" user "User.Comments")
		(21 "Eco1.User" user "User.Eco1")
		(23 "Eco2.User" user "User.Eco2")
		(25 "Edge.Cuts" user "Board Geometry/Outline")
		(27 "Margin" user)
		(31 "F.CrtYd" user "Package Geometry/Place Bound Top")
		(29 "B.CrtYd" user "Package Geometry/Place Bound Bottom")
		(35 "F.Fab" user "Ref Des/Assembly Top")
		(33 "B.Fab" user "Ref Des/Assembly Bottom")
	)
	(footprint ""
		(layer "B.Cu")
		(at 164.973 -81.407 90)
		(property "Reference" "C6P10"
			(at 0 0 90)
			(layer "B.SilkS")
			(hide yes)
			(effects
				(font
					(size 1.27 1.27)
				)
				(justify mirror)
			)
		)
		(property "Value" ""
			(at 0 0 90)
			(layer "B.Fab")
			(effects
				(font
					(size 1.27 1.27)
				)
				(justify mirror)
			)
		)
		(duplicate_pad_numbers_are_jumpers no)
		(fp_poly
			(pts
				(xy -0.3048 -0.1016) (xy -0.3048 0.9906) (xy 0.3048 0.9906) (xy 0.3048 -0.1016)
			)
			(stroke
				(width 0)
				(type default)
			)
			(fill no)
			(layer "B.CrtYd")
		)
		(fp_line
			(start 0.3048 -0.1016)
			(end 0.3048 0.9906)
			(stroke
				(width 0.1)
				(type default)
			)
			(layer "B.Fab")
		)
		(fp_line
			(start -0.3048 -0.1016)
			(end 0.3048 -0.1016)
			(stroke
				(width 0.1)
				(type default)
			)
			(layer "B.Fab")
		)
		(fp_line
			(start 0.3048 0.9906)
			(end -0.3048 0.9906)
			(stroke
				(width 0.1)
				(type default)
			)
			(layer "B.Fab")
		)
		(fp_line
			(start -0.3048 0.9906)
			(end -0.3048 -0.1016)
			(stroke
				(width 0.1)
				(type default)
			)
			(layer "B.Fab")
		)
		(pad "1" smd rect
			(at 0 0 270)
			(size 0.508 0.508)
			(layers "B.Cu" "B.Mask" "B.Paste")
			(net "P3V3_DB1200")
		)
		(pad "2" smd rect
			(at 0 0.889 270)
			(size 0.508 0.508)
			(layers "B.Cu" "B.Mask" "B.Paste")
			(net "GND")
		)
		(zone
			(layer "B.Cu")
			(hatch none 0.5)
			(connect_pads
				(clearance 0)
			)
			(min_thickness 0.25)
			(keepout
				(tracks allowed)
				(vias not_allowed)
				(pads allowed)
				(copperpour not_allowed)
				(footprints allowed)
			)
			(placement
				(enabled no)
				(sheetname "")
			)
			(fill
				(thermal_gap 0.5)
				(thermal_bridge_width 0.5)
				(island_removal_mode 0)
			)
			(polygon
				(pts
					(xy 165.227 -81.661) (xy 165.227 -81.153) (xy 165.608 -81.153) (xy 165.608 -81.661)
				)
			)
		)
		(zone
			(layer "B.Cu")
			(hatch none 0.5)
			(connect_pads
				(clearance 0)
			)
			(min_thickness 0.25)
			(keepout
				(tracks not_allowed)
				(vias allowed)
				(pads allowed)
				(copperpour not_allowed)
				(footprints allowed)
			)
			(placement
				(enabled no)
				(sheetname "")
			)
			(fill
				(thermal_gap 0.5)
				(thermal_bridge_width 0.5)
				(island_removal_mode 0)
			)
			(polygon
				(pts
					(xy 165.608 -81.661) (xy 165.608 -81.153) (xy 165.227 -81.153) (xy 165.227 -81.661)
				)
			)
		)
	)
	(footprint ""
		(layer "B.Cu")
		(at 95.922592 -82.001614)
		(property "Reference" "C8P6"
			(at 0 0 0)
			(layer "B.SilkS")
			(hide yes)
			(effects
				(font
					(size 1.27 1.27)
				)
				(justify mirror)
			)
		)
		(property "Value" ""
			(at 0 0 0)
			(layer "B.Fab")
			(effects
				(font
					(size 1.27 1.27)
				)
				(justify mirror)
			)
		)
		(duplicate_pad_numbers_are_jumpers no)
		(fp_poly
			(pts
				(xy 0.7239 -0.2159) (xy -0.7239 -0.2159) (xy -0.7239 1.9939) (xy 0.7239 1.9939)
			)
			(stroke
				(width 0)
				(type default)
			)
			(fill no)
			(layer "B.CrtYd")
		)
		(fp_line
			(start -0.7239 -0.2159)
			(end 0.7239 -0.2159)
			(stroke
				(width 0.1)
				(type default)
			)
			(layer "B.Fab")
		)
		(fp_line
			(start -0.7239 1.9939)
			(end -0.7239 -0.2159)
			(stroke
				(width 0.1)
				(type default)
			)
			(layer "B.Fab")
		)
		(fp_line
			(start 0.7239 -0.2159)
			(end 0.7239 1.9939)
			(stroke
				(width 0.1)
				(type default)
			)
			(layer "B.Fab")
		)
		(fp_line
			(start 0.7239 1.9939)
			(end -0.7239 1.9939)
			(stroke
				(width 0.1)
				(type default)
			)
			(layer "B.Fab")
		)
		(pad "1" smd rect
			(at 0 0 180)
			(size 1.27 1.016)
			(layers "B.Cu" "B.Mask" "B.Paste")
			(net "PVSA_CPU1")
		)
		(pad "2" smd rect
			(at 0 1.778 180)
			(size 1.27 1.016)
			(layers "B.Cu" "B.Mask" "B.Paste")
			(net "GND")
		)
		(zone
			(layer "B.Cu")
			(hatch none 0.5)
			(connect_pads
				(clearance 0)
			)
			(min_thickness 0.25)
			(keepout
				(tracks not_allowed)
				(vias allowed)
				(pads allowed)
				(copperpour not_allowed)
				(footprints allowed)
			)
			(placement
				(enabled no)
				(sheetname "")
			)
			(fill
				(thermal_gap 0.5)
				(thermal_bridge_width 0.5)
				(island_removal_mode 0)
			)
			(polygon
				(pts
					(xy 96.557592 -81.493614) (xy 95.287592 -81.493614) (xy 95.287592 -80.731614) (xy 96.557592 -80.731614)
				)
			)
		)
	)
	(footprint ""
		(layer "B.Cu")
		(at 403.568408 -92.993718 -90)
		(property "Reference" "R2N18"
			(at 0 0 90)
			(layer "B.SilkS")
			(hide yes)
			(effects
				(font
					(size 1.27 1.27)
				)
				(justify mirror)
			)
		)
		(property "Value" ""
			(at 0 0 90)
			(layer "B.Fab")
			(effects
				(font
					(size 1.27 1.27)
				)
				(justify mirror)
			)
		)
		(duplicate_pad_numbers_are_jumpers no)
		(fp_poly
			(pts
				(xy 0.2794 -0.1016) (xy -0.2794 -0.1016) (xy -0.2794 0.9906) (xy 0.2794 0.9906)
			)
			(stroke
				(width 0)
				(type default)
			)
			(fill no)
			(layer "B.CrtYd")
		)
		(fp_line
			(start -0.2794 0.9906)
			(end -0.2794 -0.1016)
			(stroke
				(width 0.1)
				(type default)
			)
			(layer "B.Fab")
		)
		(fp_line
			(start 0.2794 0.9906)
			(end -0.2794 0.9906)
			(stroke
				(width 0.1)
				(type default)
			)
			(layer "B.Fab")
		)
		(fp_line
			(start -0.2794 -0.1016)
			(end 0.2794 -0.1016)
			(stroke
				(width 0.1)
				(type default)
			)
			(layer "B.Fab")
		)
		(fp_line
			(start 0.2794 -0.1016)
			(end 0.2794 0.9906)
			(stroke
				(width 0.1)
				(type default)
			)
			(layer "B.Fab")
		)
		(pad "1" smd rect
			(at 0 0 90)
			(size 0.508 0.508)
			(layers "B.Cu" "B.Mask" "B.Paste")
			(net "FM_BOARD_SKU_ID4")
		)
		(pad "2" smd rect
			(at 0 0.889 90)
			(size 0.508 0.508)
			(layers "B.Cu" "B.Mask" "B.Paste")
			(net "GND")
		)
		(zone
			(layer "B.Cu")
			(hatch none 0.5)
			(connect_pads
				(clearance 0)
			)
			(min_thickness 0.25)
			(keepout
				(tracks not_allowed)
				(vias allowed)
				(pads allowed)
				(copperpour not_allowed)
				(footprints allowed)
			)
			(placement
				(enabled no)
				(sheetname "")
			)
			(fill
				(thermal_gap 0.5)
				(thermal_bridge_width 0.5)
				(island_removal_mode 0)
			)
			(polygon
				(pts
					(xy 402.933408 -92.739718) (xy 402.933408 -93.247718) (xy 403.314408 -93.247718) (xy 403.314408 -92.739718)
				)
			)
		)
		(zone
			(layer "B.Cu")
			(hatch none 0.5)
			(connect_pads
				(clearance 0)
			)
			(min_thickness 0.25)
			(keepout
				(tracks allowed)
				(vias not_allowed)
				(pads allowed)
				(copperpour not_allowed)
				(footprints allowed)
			)
			(placement
				(enabled no)
				(sheetname "")
			)
			(fill
				(thermal_gap 0.5)
				(thermal_bridge_width 0.5)
				(island_removal_mode 0)
			)
			(polygon
				(pts
					(xy 403.314408 -92.739718) (xy 403.314408 -93.247718) (xy 402.933408 -93.247718) (xy 402.933408 -92.739718)
				)
			)
		)
	)
)
